# T6G (Grand Teton) — schematic netlist excerpt (pin names and nets, part order shuffled) for the footprints in the layout excerpt that follows; sources: Cadence DE-HDL packaged netlist, KiCad conversion of 04192023_DAF0TMB3IC0_F0TG_MB_C_brd_V02_OCP.brd

PR128  Q_RES  1K 1% EMPTY  pkg 0402LF  page 207 : A = PVDD11_S3_P0_RESET_N_R ; B = PVDD18_S5_P0
PR340  Q_RES  0 5% CHIP  pkg 0402LF  page 218 : A = PVDDCR_CPU1_P1_PVCC ; B = P5V_AUX

(kicad_pcb
	(version 20260206)
	(generator "pcbnew")
	(generator_version "10.0")
	(general
		(thickness 1.6)
		(legacy_teardrops no)
	)
	(paper "A4")
	(title_block
		(title "04192023_DAF0TMB3IC0_F0TG_MB_C_brd_V02_OCP.brd")
		(comment 1 "Grand Teton / footprints 688-689 of 8354")
	)
	(layers
		(0 "F.Cu" signal "TOP")
		(4 "In1.Cu" signal "GND")
		(6 "In2.Cu" signal "IN1")
		(8 "In3.Cu" signal "GND1")
		(10 "In4.Cu" signal "IN2")
		(12 "In5.Cu" signal "GND2")
		(14 "In6.Cu" signal "IN3")
		(16 "In7.Cu" signal "GND3")
		(18 "In8.Cu" signal "VCC")
		(20 "In9.Cu" signal "VCC1")
		(22 "In10.Cu" signal "GND4")
		(24 "In11.Cu" signal "IN4")
		(26 "In12.Cu" signal "GND5")
		(28 "In13.Cu" signal "IN5")
		(30 "In14.Cu" signal "GND6")
		(32 "In15.Cu" signal "IN6")
		(34 "In16.Cu" signal "GND7")
		(2 "B.Cu" signal "BOTTOM")
		(9 "F.Adhes" user "F.Adhesive")
		(11 "B.Adhes" user "B.Adhesive")
		(13 "F.Paste" user "Package Geometry/Pastemask Top")
		(15 "B.Paste" user "Package Geometry/Pastemask Bottom")
		(5 "F.SilkS" user "Ref Des/Silkscreen Top")
		(7 "B.SilkS" user "Ref Des/Silkscreen Bottom")
		(1 "F.Mask" user "Board Geometry/Soldermask Top")
		(3 "B.Mask" user "Board Geometry/Soldermask Bottom")
		(17 "Dwgs.User" user "User.Drawings")
		(19 "Cmts.User" user "User.Comments")
		(21 "Eco1.User" user "User.Eco1")
		(23 "Eco2.User" user "User.Eco2")
		(25 "Edge.Cuts" user "Board Geometry/Outline")
		(27 "Margin" user)
		(31 "F.CrtYd" user "Package Geometry/Place Bound Top")
		(29 "B.CrtYd" user "Package Geometry/Place Bound Bottom")
		(35 "F.Fab" user "Ref Des/Assembly Top")
		(33 "B.Fab" user "Ref Des/Assembly Bottom")
	)
	(footprint ""
		(layer "F.Cu")
		(at 24.057102 -351.621598 90)
		(property "Reference" "PR340"
			(at 0 0 90)
			(layer "F.SilkS")
			(hide yes)
			(effects
				(font
					(size 1.27 1.27)
				)
			)
		)
		(property "Value" ""
			(at 0 0 90)
			(layer "F.Fab")
			(effects
				(font
					(size 1.27 1.27)
				)
			)
		)
		(duplicate_pad_numbers_are_jumpers no)
		(fp_line
			(start 0.7874 -0.4064)
			(end 0.7874 0.4064)
			(stroke
				(width 0.1524)
				(type default)
			)
			(layer "F.SilkS")
		)
		(fp_line
			(start -0.7874 -0.4064)
			(end 0.7874 -0.4064)
			(stroke
				(width 0.1524)
				(type default)
			)
			(layer "F.SilkS")
		)
		(fp_line
			(start 0.7874 0.4064)
			(end -0.7874 0.4064)
			(stroke
				(width 0.1524)
				(type default)
			)
			(layer "F.SilkS")
		)
		(fp_line
			(start -0.7874 0.4064)
			(end -0.7874 -0.4064)
			(stroke
				(width 0.1524)
				(type default)
			)
			(layer "F.SilkS")
		)
		(fp_line
			(start -0.12065 -0.305054)
			(end -0.12065 -0.2794)
			(stroke
				(width 0.1)
				(type default)
			)
			(layer "F.Fab")
		)
		(fp_line
			(start -0.67945 -0.305054)
			(end -0.12065 -0.305054)
			(stroke
				(width 0.1)
				(type default)
			)
			(layer "F.Fab")
		)
		(fp_line
			(start 0.67945 -0.3048)
			(end 0.67945 0.3048)
			(stroke
				(width 0.1)
				(type default)
			)
			(layer "F.Fab")
		)
		(fp_line
			(start 0.12065 -0.3048)
			(end 0.67945 -0.3048)
			(stroke
				(width 0.1)
				(type default)
			)
			(layer "F.Fab")
		)
		(fp_line
			(start 0.12065 -0.2794)
			(end 0.12065 -0.3048)
			(stroke
				(width 0.1)
				(type default)
			)
			(layer "F.Fab")
		)
		(fp_line
			(start -0.12065 -0.2794)
			(end 0.12065 -0.2794)
			(stroke
				(width 0.1)
				(type default)
			)
			(layer "F.Fab")
		)
		(fp_line
			(start 0.120396 0.2794)
			(end -0.12065 0.2794)
			(stroke
				(width 0.1)
				(type default)
			)
			(layer "F.Fab")
		)
		(fp_line
			(start -0.12065 0.2794)
			(end -0.12065 0.3048)
			(stroke
				(width 0.1)
				(type default)
			)
			(layer "F.Fab")
		)
		(fp_line
			(start 0.67945 0.3048)
			(end 0.120396 0.3048)
			(stroke
				(width 0.1)
				(type default)
			)
			(layer "F.Fab")
		)
		(fp_line
			(start 0.120396 0.3048)
			(end 0.120396 0.2794)
			(stroke
				(width 0.1)
				(type default)
			)
			(layer "F.Fab")
		)
		(fp_line
			(start -0.12065 0.3048)
			(end -0.67945 0.3048)
			(stroke
				(width 0.1)
				(type default)
			)
			(layer "F.Fab")
		)
		(fp_line
			(start -0.67945 0.3048)
			(end -0.67945 -0.305054)
			(stroke
				(width 0.1)
				(type default)
			)
			(layer "F.Fab")
		)
		(pad "1" smd circle
			(at -0.40005 0 90)
			(size 0 0)
			(layers "F.Cu" "F.Mask" "F.Paste")
			(net "PVDDCR_CPU1_P1_PVCC")
		)
		(pad "2" smd circle
			(at 0.40005 0 90)
			(size 0 0)
			(layers "F.Cu" "F.Mask" "F.Paste")
			(net "P5V_AUX")
		)
	)
	(footprint ""
		(layer "F.Cu")
		(at 414.325562 -362.804964 180)
		(property "Reference" "PR128"
			(at 0 0 180)
			(layer "F.SilkS")
			(hide yes)
			(effects
				(font
					(size 1.27 1.27)
				)
			)
		)
		(property "Value" ""
			(at 0 0 180)
			(layer "F.Fab")
			(effects
				(font
					(size 1.27 1.27)
				)
			)
		)
		(duplicate_pad_numbers_are_jumpers no)
		(fp_line
			(start 0.7874 0.4064)
			(end -0.7874 0.4064)
			(stroke
				(width 0.1524)
				(type default)
			)
			(layer "F.SilkS")
		)
		(fp_line
			(start 0.7874 -0.4064)
			(end 0.7874 0.4064)
			(stroke
				(width 0.1524)
				(type default)
			)
			(layer "F.SilkS")
		)
		(fp_line
			(start -0.7874 0.4064)
			(end -0.7874 -0.4064)
			(stroke
				(width 0.1524)
				(type default)
			)
			(layer "F.SilkS")
		)
		(fp_line
			(start -0.7874 -0.4064)
			(end 0.7874 -0.4064)
			(stroke
				(width 0.1524)
				(type default)
			)
			(layer "F.SilkS")
		)
		(fp_line
			(start 0.67945 0.3048)
			(end 0.120396 0.3048)
			(stroke
				(width 0.1)
				(type default)
			)
			(layer "F.Fab")
		)
		(fp_line
			(start 0.67945 -0.3048)
			(end 0.67945 0.3048)
			(stroke
				(width 0.1)
				(type default)
			)
			(layer "F.Fab")
		)
		(fp_line
			(start 0.12065 -0.2794)
			(end 0.12065 -0.3048)
			(stroke
				(width 0.1)
				(type default)
			)
			(layer "F.Fab")
		)
		(fp_line
			(start 0.12065 -0.3048)
			(end 0.67945 -0.3048)
			(stroke
				(width 0.1)
				(type default)
			)
			(layer "F.Fab")
		)
		(fp_line
			(start 0.120396 0.3048)
			(end 0.120396 0.2794)
			(stroke
				(width 0.1)
				(type default)
			)
			(layer "F.Fab")
		)
		(fp_line
			(start 0.120396 0.2794)
			(end -0.12065 0.2794)
			(stroke
				(width 0.1)
				(type default)
			)
			(layer "F.Fab")
		)
		(fp_line
			(start -0.12065 0.3048)
			(end -0.67945 0.3048)
			(stroke
				(width 0.1)
				(type default)
			)
			(layer "F.Fab")
		)
		(fp_line
			(start -0.12065 0.2794)
			(end -0.12065 0.3048)
			(stroke
				(width 0.1)
				(type default)
			)
			(layer "F.Fab")
		)
		(fp_line
			(start -0.12065 -0.2794)
			(end 0.12065 -0.2794)
			(stroke
				(width 0.1)
				(type default)
			)
			(layer "F.Fab")
		)
		(fp_line
			(start -0.12065 -0.305054)
			(end -0.12065 -0.2794)
			(stroke
				(width 0.1)
				(type default)
			)
			(layer "F.Fab")
		)
		(fp_line
			(start -0.67945 0.3048)
			(end -0.67945 -0.305054)
			(stroke
				(width 0.1)
				(type default)
			)
			(layer "F.Fab")
		)
		(fp_line
			(start -0.67945 -0.305054)
			(end -0.12065 -0.305054)
			(stroke
				(width 0.1)
				(type default)
			)
			(layer "F.Fab")
		)
		(pad "1" smd circle
			(at -0.40005 0 180)
			(size 0 0)
			(layers "F.Cu" "F.Mask" "F.Paste")
			(net "PVDD11_S3_P0_RESET_N_R")
		)
		(pad "2" smd circle
			(at 0.40005 0 180)
			(size 0 0)
			(layers "F.Cu" "F.Mask" "F.Paste")
			(net "PVDD18_S5_P0")
		)
	)
)
